#ISCELL
  mstr_misc dns *
  *
#ISCELL
  mstr_symbols intel_corp_bpage *
  *
#ISCELL
  mstr_standard offpage *
  page144_i100
#ISCELL
  mstr_standard offpage *
  page144_i101
#ISCELL
  mstr_standard offpage *
  page144_i102
#ISCELL
  mstr_standard offpage *
  page144_i103
#ISCELL
  mstr_standard offpage *
  page144_i104
#ISCELL
  mstr_standard offpage *
  page144_i105
#ISCELL
  mstr_standard offpage *
  page144_i106
#ISCELL
  mstr_standard offpage *
  page144_i107
#ISCELL
  mstr_standard offpage *
  page144_i108
#ISCELL
  mstr_standard offpage *
  page144_i109
#ISCELL
  mstr_standard offpage *
  page144_i110
#ISCELL
  mstr_standard offpage *
  page144_i111
#ISCELL
  mstr_standard offpage *
  page144_i112
#ISCELL
  mstr_standard offpage *
  page144_i113
#CELL
  mstr_discrete res *
  page144_i114
#ISCELL
  mstr_standard offpage *
  page144_i116
#CELL
  mstr_discrete res *
  page144_i118
#ISCELL
  mstr_standard offpage *
  page144_i121
#ISCELL
  mstr_standard offpage *
  page144_i125
#ISCELL
  mstr_standard offpage *
  page144_i126
#ISCELL
  mstr_standard offpage *
  page144_i127
#ISCELL
  mstr_standard offpage *
  page144_i128
#ISCELL
  mstr_standard offpage *
  page144_i129
#ISCELL
  mstr_standard offpage *
  page144_i130
#ISCELL
  mstr_standard offpage *
  page144_i133
#ISCELL
  mstr_standard offpage *
  page144_i134
#ISCELL
  mstr_standard offpage *
  page144_i135
#ISCELL
  mstr_standard offpage *
  page144_i136
#ISCELL
  mstr_standard offpage *
  page144_i137
#ISCELL
  mstr_standard offpage *
  page144_i138
#CELL
  mstr_discrete res *
  page144_i139
#CELL
  mstr_discrete res *
  page144_i140
#CELL
  mstr_discrete res *
  page144_i141
#ISCELL
  mstr_symbols gnd *
  page144_i142
#ISCELL
  mstr_symbols gnd *
  page144_i143
#ISCELL
  mstr_symbols gnd *
  page144_i144
#ISCELL
  mstr_standard offpage *
  page144_i146
#ISCELL
  mstr_standard offpage *
  page144_i147
#CELL
  mstr_discrete res *
  page144_i148
#ISCELL
  mstr_standard offpage *
  page144_i149
#CELL
  w_hdl 18kr2f-gp *
  page144_i150
#CELL
  mstr_discrete res *
  page144_i151
#ISCELL
  mstr_standard offpage *
  page144_i152
#ISCELL
  mstr_standard offpage *
  page144_i153
#ISCELL
  mstr_standard offpage *
  page144_i28
#ISCELL
  mstr_standard offpage *
  page144_i29
#ISCELL
  mstr_standard offpage *
  page144_i32
#ISCELL
  mstr_standard offpage *
  page144_i37
#ISCELL
  mstr_standard offpage *
  page144_i44
#ISCELL
  mstr_standard offpage *
  page144_i47
#ISCELL
  mstr_standard offpage *
  page144_i48
#ISCELL
  mstr_standard offpage *
  page144_i49
#ISCELL
  mstr_standard offpage *
  page144_i50
#ISCELL
  mstr_standard offpage *
  page144_i51
#ISCELL
  mstr_standard offpage *
  page144_i52
#ISCELL
  mstr_standard offpage *
  page144_i53
#ISCELL
  mstr_standard offpage *
  page144_i54
#ISCELL
  mstr_standard offpage *
  page144_i55
#ISCELL
  mstr_standard offpage *
  page144_i56
#CELL
  mstr_discrete res *
  page144_i57
#CELL
  mstr_discrete res *
  page144_i58
#CELL
  mstr_discrete res *
  page144_i59
#ISCELL
  mstr_standard offpage *
  page144_i67
#ISCELL
  mstr_standard offpage *
  page144_i70
#ISCELL
  mstr_symbols gnd *
  page144_i72
#ISCELL
  mstr_standard offpage *
  page144_i74
#ISCELL
  mstr_standard offpage *
  page144_i93
#CELL
  w_hdl ast2520a1-gp-gp *
  page144_i95
#ISCELL
  mstr_standard offpage *
  page144_i96
#ISCELL
  mstr_standard offpage *
  page144_i97
